# S9S_MB_2U (Grand Teton) — schematic netlist excerpt (pin names and nets, part order shuffled) for the footprints in the layout excerpt that follows; sources: Cadence DE-HDL packaged netlist, KiCad conversion of 03242023_DA0F0TMBIJ0_F0T_Motherboard_J_brd_V01_OCP.brd

C173  Q_CAP  0.047UF 25V 10% X7R  pkg C0402  page 210 : A = P3V3_AUX_CLK_GEN_VDDA100M_CK440 ; B = GND
R673  Q_RES  33.2 1% CHIP  pkg 0402LF  page 230 : A = I3C_SPD_DDREFGH_CPU1_SDA ; B = I3C_SPD_DDREFGH_CPU1_R_SDA

(kicad_pcb
	(version 20260206)
	(generator "pcbnew")
	(generator_version "10.0")
	(general
		(thickness 1.6)
		(legacy_teardrops no)
	)
	(paper "A4")
	(title_block
		(title "03242023_DA0F0TMBIJ0_F0T_Motherboard_J_brd_V01_OCP.brd")
		(comment 1 "Grand Teton / footprints 5714-5715 of 6105")
	)
	(layers
		(0 "F.Cu" signal "TOP")
		(4 "In1.Cu" signal "GND")
		(6 "In2.Cu" signal "IN1")
		(8 "In3.Cu" signal "GND1")
		(10 "In4.Cu" signal "IN2")
		(12 "In5.Cu" signal "GND2")
		(14 "In6.Cu" signal "IN3")
		(16 "In7.Cu" signal "GND3")
		(18 "In8.Cu" signal "VCC")
		(20 "In9.Cu" signal "VCC1")
		(22 "In10.Cu" signal "GND4")
		(24 "In11.Cu" signal "IN4")
		(26 "In12.Cu" signal "GND5")
		(28 "In13.Cu" signal "IN5")
		(30 "In14.Cu" signal "GND6")
		(32 "In15.Cu" signal "IN6")
		(34 "In16.Cu" signal "GND7")
		(2 "B.Cu" signal "BOTTOM")
		(9 "F.Adhes" user "F.Adhesive")
		(11 "B.Adhes" user "B.Adhesive")
		(13 "F.Paste" user "Package Geometry/Pastemask Top")
		(15 "B.Paste" user "Package Geometry/Pastemask Bottom")
		(5 "F.SilkS" user "Ref Des/Silkscreen Top")
		(7 "B.SilkS" user "Ref Des/Silkscreen Bottom")
		(1 "F.Mask" user "Board Geometry/Soldermask Top")
		(3 "B.Mask" user "Board Geometry/Soldermask Bottom")
		(17 "Dwgs.User" user "User.Drawings")
		(19 "Cmts.User" user "User.Comments")
		(21 "Eco1.User" user "User.Eco1")
		(23 "Eco2.User" user "User.Eco2")
		(25 "Edge.Cuts" user "Board Geometry/Outline")
		(27 "Margin" user)
		(31 "F.CrtYd" user "Package Geometry/Place Bound Top")
		(29 "B.CrtYd" user "Package Geometry/Place Bound Bottom")
		(35 "F.Fab" user "Ref Des/Assembly Top")
		(33 "B.Fab" user "Ref Des/Assembly Bottom")
	)
	(footprint ""
		(layer "B.Cu")
		(at 256.286 -96.992948 -90)
		(property "Reference" "C173"
			(at 0 0 90)
			(layer "B.SilkS")
			(hide yes)
			(effects
				(font
					(size 1.27 1.27)
				)
				(justify mirror)
			)
		)
		(property "Value" ""
			(at 0 0 90)
			(layer "B.Fab")
			(effects
				(font
					(size 1.27 1.27)
				)
				(justify mirror)
			)
		)
		(duplicate_pad_numbers_are_jumpers no)
		(fp_line
			(start -0.7874 0.4064)
			(end 0.7874 0.4064)
			(stroke
				(width 0.1524)
				(type default)
			)
			(layer "B.SilkS")
		)
		(fp_line
			(start 0.7874 0.4064)
			(end 0.7874 -0.4064)
			(stroke
				(width 0.1524)
				(type default)
			)
			(layer "B.SilkS")
		)
		(fp_line
			(start -0.7874 -0.4064)
			(end -0.7874 0.4064)
			(stroke
				(width 0.1524)
				(type default)
			)
			(layer "B.SilkS")
		)
		(fp_line
			(start 0.7874 -0.4064)
			(end -0.7874 -0.4064)
			(stroke
				(width 0.1524)
				(type default)
			)
			(layer "B.SilkS")
		)
		(fp_line
			(start -0.67945 0.3048)
			(end -0.120396 0.3048)
			(stroke
				(width 0.1)
				(type default)
			)
			(layer "B.Fab")
		)
		(fp_line
			(start -0.120396 0.3048)
			(end -0.120396 0.2794)
			(stroke
				(width 0.1)
				(type default)
			)
			(layer "B.Fab")
		)
		(fp_line
			(start 0.12065 0.3048)
			(end 0.67945 0.3048)
			(stroke
				(width 0.1)
				(type default)
			)
			(layer "B.Fab")
		)
		(fp_line
			(start 0.67945 0.3048)
			(end 0.67945 -0.305054)
			(stroke
				(width 0.1)
				(type default)
			)
			(layer "B.Fab")
		)
		(fp_line
			(start -0.120396 0.2794)
			(end 0.12065 0.2794)
			(stroke
				(width 0.1)
				(type default)
			)
			(layer "B.Fab")
		)
		(fp_line
			(start 0.12065 0.2794)
			(end 0.12065 0.3048)
			(stroke
				(width 0.1)
				(type default)
			)
			(layer "B.Fab")
		)
		(fp_line
			(start -0.12065 -0.2794)
			(end -0.12065 -0.3048)
			(stroke
				(width 0.1)
				(type default)
			)
			(layer "B.Fab")
		)
		(fp_line
			(start 0.12065 -0.2794)
			(end -0.12065 -0.2794)
			(stroke
				(width 0.1)
				(type default)
			)
			(layer "B.Fab")
		)
		(fp_line
			(start -0.67945 -0.3048)
			(end -0.67945 0.3048)
			(stroke
				(width 0.1)
				(type default)
			)
			(layer "B.Fab")
		)
		(fp_line
			(start -0.12065 -0.3048)
			(end -0.67945 -0.3048)
			(stroke
				(width 0.1)
				(type default)
			)
			(layer "B.Fab")
		)
		(fp_line
			(start 0.12065 -0.305054)
			(end 0.12065 -0.2794)
			(stroke
				(width 0.1)
				(type default)
			)
			(layer "B.Fab")
		)
		(fp_line
			(start 0.67945 -0.305054)
			(end 0.12065 -0.305054)
			(stroke
				(width 0.1)
				(type default)
			)
			(layer "B.Fab")
		)
		(pad "1" smd circle
			(at 0.40005 0 90)
			(size 0 0)
			(layers "B.Cu" "B.Mask" "B.Paste")
			(net "P3V3_AUX_CLK_GEN_VDDA100M_CK440")
		)
		(pad "2" smd circle
			(at -0.40005 0 90)
			(size 0 0)
			(layers "B.Cu" "B.Mask" "B.Paste")
			(net "GND")
		)
	)
	(footprint ""
		(layer "B.Cu")
		(at 153.232104 -190.36411 90)
		(property "Reference" "R673"
			(at 0 0 90)
			(layer "B.SilkS")
			(hide yes)
			(effects
				(font
					(size 1.27 1.27)
				)
				(justify mirror)
			)
		)
		(property "Value" ""
			(at 0 0 90)
			(layer "B.Fab")
			(effects
				(font
					(size 1.27 1.27)
				)
				(justify mirror)
			)
		)
		(duplicate_pad_numbers_are_jumpers no)
		(fp_line
			(start 0.7874 -0.4064)
			(end -0.7874 -0.4064)
			(stroke
				(width 0.1524)
				(type default)
			)
			(layer "B.SilkS")
		)
		(fp_line
			(start -0.7874 -0.4064)
			(end -0.7874 0.4064)
			(stroke
				(width 0.1524)
				(type default)
			)
			(layer "B.SilkS")
		)
		(fp_line
			(start 0.7874 0.4064)
			(end 0.7874 -0.4064)
			(stroke
				(width 0.1524)
				(type default)
			)
			(layer "B.SilkS")
		)
		(fp_line
			(start -0.7874 0.4064)
			(end 0.7874 0.4064)
			(stroke
				(width 0.1524)
				(type default)
			)
			(layer "B.SilkS")
		)
		(fp_line
			(start 0.67945 -0.305054)
			(end 0.12065 -0.305054)
			(stroke
				(width 0.1)
				(type default)
			)
			(layer "B.Fab")
		)
		(fp_line
			(start 0.12065 -0.305054)
			(end 0.12065 -0.2794)
			(stroke
				(width 0.1)
				(type default)
			)
			(layer "B.Fab")
		)
		(fp_line
			(start -0.12065 -0.3048)
			(end -0.67945 -0.3048)
			(stroke
				(width 0.1)
				(type default)
			)
			(layer "B.Fab")
		)
		(fp_line
			(start -0.67945 -0.3048)
			(end -0.67945 0.3048)
			(stroke
				(width 0.1)
				(type default)
			)
			(layer "B.Fab")
		)
		(fp_line
			(start 0.12065 -0.2794)
			(end -0.12065 -0.2794)
			(stroke
				(width 0.1)
				(type default)
			)
			(layer "B.Fab")
		)
		(fp_line
			(start -0.12065 -0.2794)
			(end -0.12065 -0.3048)
			(stroke
				(width 0.1)
				(type default)
			)
			(layer "B.Fab")
		)
		(fp_line
			(start 0.12065 0.2794)
			(end 0.12065 0.3048)
			(stroke
				(width 0.1)
				(type default)
			)
			(layer "B.Fab")
		)
		(fp_line
			(start -0.120396 0.2794)
			(end 0.12065 0.2794)
			(stroke
				(width 0.1)
				(type default)
			)
			(layer "B.Fab")
		)
		(fp_line
			(start 0.67945 0.3048)
			(end 0.67945 -0.305054)
			(stroke
				(width 0.1)
				(type default)
			)
			(layer "B.Fab")
		)
		(fp_line
			(start 0.12065 0.3048)
			(end 0.67945 0.3048)
			(stroke
				(width 0.1)
				(type default)
			)
			(layer "B.Fab")
		)
		(fp_line
			(start -0.120396 0.3048)
			(end -0.120396 0.2794)
			(stroke
				(width 0.1)
				(type default)
			)
			(layer "B.Fab")
		)
		(fp_line
			(start -0.67945 0.3048)
			(end -0.120396 0.3048)
			(stroke
				(width 0.1)
				(type default)
			)
			(layer "B.Fab")
		)
		(pad "1" smd circle
			(at 0.40005 0 270)
			(size 0 0)
			(layers "B.Cu" "B.Mask" "B.Paste")
			(net "I3C_SPD_DDREFGH_CPU1_SDA")
		)
		(pad "2" smd circle
			(at -0.40005 0 270)
			(size 0 0)
			(layers "B.Cu" "B.Mask" "B.Paste")
			(net "I3C_SPD_DDREFGH_CPU1_R_SDA")
		)
	)
)
